(kicad_pcb
	(version 20260206)
	(generator "pcbnew")
	(generator_version "10.0")
	(general
		(thickness 1.6)
		(legacy_teardrops no)
	)
	(paper "A4")
	(title_block
		(title "12092022_DA0F0TYB4D0_F0T_Panel_BD_Front_D_brd_v02_OCP.brd")
		(comment 1 "Grand Teton / footprints 105-108 of 128")
	)
	(layers
		(0 "F.Cu" signal "TOP")
		(4 "In1.Cu" signal "GND")
		(6 "In2.Cu" signal "GND1")
		(2 "B.Cu" signal "BOTTOM")
		(9 "F.Adhes" user "F.Adhesive")
		(11 "B.Adhes" user "B.Adhesive")
		(13 "F.Paste" user "Package Geometry/Pastemask Top")
		(15 "B.Paste" user "Package Geometry/Pastemask Bottom")
		(5 "F.SilkS" user "Ref Des/Silkscreen Top")
		(7 "B.SilkS" user "Ref Des/Silkscreen Bottom")
		(1 "F.Mask" user "Board Geometry/Soldermask Top")
		(3 "B.Mask" user "Board Geometry/Soldermask Bottom")
		(17 "Dwgs.User" user "User.Drawings")
		(19 "Cmts.User" user "User.Comments")
		(21 "Eco1.User" user "User.Eco1")
		(23 "Eco2.User" user "User.Eco2")
		(25 "Edge.Cuts" user "Board Geometry/Outline")
		(27 "Margin" user)
		(31 "F.CrtYd" user "Package Geometry/Place Bound Top")
		(29 "B.CrtYd" user "Package Geometry/Place Bound Bottom")
		(35 "F.Fab" user "Ref Des/Assembly Top")
		(33 "B.Fab" user "Ref Des/Assembly Bottom")
	)
	(footprint ""
		(layer "F.Cu")
		(at 3.937 -49.784)
		(property "Reference" "R57"
			(at -2.413 0.15367 0)
			(unlocked yes)
			(layer "F.SilkS")
			(effects
				(font
					(size 0.7874 0.5842)
					(thickness 0.1524)
				)
			)
		)
		(property "Value" ""
			(at 0 0 0)
			(layer "F.Fab")
			(effects
				(font
					(size 1.27 1.27)
				)
			)
		)
		(duplicate_pad_numbers_are_jumpers no)
		(fp_line
			(start -0.7874 -0.4064)
			(end 0.7874 -0.4064)
			(stroke
				(width 0.1524)
				(type default)
			)
			(layer "F.SilkS")
		)
		(fp_line
			(start -0.7874 0.4064)
			(end -0.7874 -0.4064)
			(stroke
				(width 0.1524)
				(type default)
			)
			(layer "F.SilkS")
		)
		(fp_line
			(start 0.7874 -0.4064)
			(end 0.7874 0.4064)
			(stroke
				(width 0.1524)
				(type default)
			)
			(layer "F.SilkS")
		)
		(fp_line
			(start 0.7874 0.4064)
			(end -0.7874 0.4064)
			(stroke
				(width 0.1524)
				(type default)
			)
			(layer "F.SilkS")
		)
		(fp_line
			(start -0.67945 -0.305054)
			(end -0.12065 -0.305054)
			(stroke
				(width 0.1)
				(type default)
			)
			(layer "F.Fab")
		)
		(fp_line
			(start -0.67945 0.3048)
			(end -0.67945 -0.305054)
			(stroke
				(width 0.1)
				(type default)
			)
			(layer "F.Fab")
		)
		(fp_line
			(start -0.12065 -0.305054)
			(end -0.12065 -0.2794)
			(stroke
				(width 0.1)
				(type default)
			)
			(layer "F.Fab")
		)
		(fp_line
			(start -0.12065 -0.2794)
			(end 0.12065 -0.2794)
			(stroke
				(width 0.1)
				(type default)
			)
			(layer "F.Fab")
		)
		(fp_line
			(start -0.12065 0.2794)
			(end -0.12065 0.3048)
			(stroke
				(width 0.1)
				(type default)
			)
			(layer "F.Fab")
		)
		(fp_line
			(start -0.12065 0.3048)
			(end -0.67945 0.3048)
			(stroke
				(width 0.1)
				(type default)
			)
			(layer "F.Fab")
		)
		(fp_line
			(start 0.120396 0.2794)
			(end -0.12065 0.2794)
			(stroke
				(width 0.1)
				(type default)
			)
			(layer "F.Fab")
		)
		(fp_line
			(start 0.120396 0.3048)
			(end 0.120396 0.2794)
			(stroke
				(width 0.1)
				(type default)
			)
			(layer "F.Fab")
		)
		(fp_line
			(start 0.12065 -0.3048)
			(end 0.67945 -0.3048)
			(stroke
				(width 0.1)
				(type default)
			)
			(layer "F.Fab")
		)
		(fp_line
			(start 0.12065 -0.2794)
			(end 0.12065 -0.3048)
			(stroke
				(width 0.1)
				(type default)
			)
			(layer "F.Fab")
		)
		(fp_line
			(start 0.67945 -0.3048)
			(end 0.67945 0.3048)
			(stroke
				(width 0.1)
				(type default)
			)
			(layer "F.Fab")
		)
		(fp_line
			(start 0.67945 0.3048)
			(end 0.120396 0.3048)
			(stroke
				(width 0.1)
				(type default)
			)
			(layer "F.Fab")
		)
		(pad "1" smd circle
			(at -0.40005 0)
			(size 0 0)
			(layers "F.Cu" "F.Mask" "F.Paste")
			(net "P3V3_STBY")
		)
		(pad "2" smd circle
			(at 0.40005 0)
			(size 0 0)
			(layers "F.Cu" "F.Mask" "F.Paste")
			(net "PD_FRU_A1")
		)
	)
	(footprint ""
		(layer "F.Cu")
		(at 95.25 -155.194 -90)
		(property "Reference" "J7"
			(at -4.25577 0.54356 0)
			(unlocked yes)
			(layer "F.SilkS")
			(effects
				(font
					(size 0.7874 0.5842)
					(thickness 0.1524)
				)
				(justify left)
			)
		)
		(property "Value" ""
			(at 0 0 270)
			(layer "F.Fab")
			(effects
				(font
					(size 1.27 1.27)
				)
			)
		)
		(duplicate_pad_numbers_are_jumpers no)
		(fp_line
			(start -1.2192 2.1082)
			(end -1.2192 -2.1082)
			(stroke
				(width 0.1524)
				(type default)
			)
			(layer "F.SilkS")
		)
		(fp_line
			(start 1.2192 2.1082)
			(end -1.2192 2.1082)
			(stroke
				(width 0.1524)
				(type default)
			)
			(layer "F.SilkS")
		)
		(fp_line
			(start -1.2192 -2.1082)
			(end 1.2192 -2.1082)
			(stroke
				(width 0.1524)
				(type default)
			)
			(layer "F.SilkS")
		)
		(fp_line
			(start 1.2192 -2.1082)
			(end 1.2192 2.1082)
			(stroke
				(width 0.1524)
				(type default)
			)
			(layer "F.SilkS")
		)
		(pad "" np_thru_hole circle
			(at -2.8829 -1.27 180)
			(size 1.0414 1.0414)
			(drill 1.0414)
			(layers "*.Cu" "*.Mask")
			(clearance 0.381)
			(thermal_gap 0.381)
		)
		(pad "" np_thru_hole circle
			(at -2.8829 1.27 180)
			(size 1.0414 1.0414)
			(drill 1.0414)
			(layers "*.Cu" "*.Mask")
			(clearance 0.381)
			(thermal_gap 0.381)
		)
		(pad "" np_thru_hole circle
			(at 3.4671 -1.27 180)
			(size 1.0414 1.0414)
			(drill 1.0414)
			(layers "*.Cu" "*.Mask")
			(clearance 0.381)
			(thermal_gap 0.381)
		)
		(pad "" np_thru_hole circle
			(at 3.4671 1.27 180)
			(size 1.0414 1.0414)
			(drill 1.0414)
			(layers "*.Cu" "*.Mask")
			(clearance 0.381)
			(thermal_gap 0.381)
		)
		(pad "1" smd rect
			(at 0.8255 -0.249936 180)
			(size 0.3048 0.508)
			(layers "F.Cu" "F.Mask" "F.Paste")
			(net "DELTA_L_85_10INCH_TOP_DP")
		)
		(pad "2" smd rect
			(at 0.8255 0.249936 180)
			(size 0.3048 0.508)
			(layers "F.Cu" "F.Mask" "F.Paste")
			(net "DELTA_L_85_10INCH_TOP_DN")
		)
		(pad "3" smd circle
			(at 0 0 270)
			(size 0 0)
			(layers "F.Cu" "F.Mask" "F.Paste")
			(net "GND1")
		)
		(zone
			(layer "F.Cu")
			(hatch none 0.5)
			(connect_pads
				(clearance 0)
			)
			(min_thickness 0.25)
			(keepout
				(tracks not_allowed)
				(vias allowed)
				(pads allowed)
				(copperpour not_allowed)
				(footprints allowed)
			)
			(placement
				(enabled no)
				(sheetname "")
			)
			(fill
				(thermal_gap 0.5)
				(thermal_bridge_width 0.5)
				(island_removal_mode 0)
			)
			(polygon
				(pts
					(xy 95.79864 -154.0764) (xy 95.703136 -154.0764) (xy 95.703136 -154.6733) (xy 95.296736 -154.6733)
					(xy 95.296736 -154.0764) (xy 95.203264 -154.0764) (xy 95.203264 -154.6733) (xy 94.796864 -154.6733)
					(xy 94.796864 -154.0764) (xy 94.70136 -154.0764) (xy 94.70136 -154.7749) (xy 95.79864 -154.7749)
				)
			)
		)
		(zone
			(layers "F.Cu" "B.Cu" "In1.Cu" "In2.Cu")
			(hatch none 0.5)
			(connect_pads
				(clearance 0)
			)
			(min_thickness 0.25)
			(keepout
				(tracks not_allowed)
				(vias allowed)
				(pads allowed)
				(copperpour not_allowed)
				(footprints allowed)
			)
			(placement
				(enabled no)
				(sheetname "")
			)
			(fill
				(thermal_gap 0.5)
				(thermal_bridge_width 0.5)
				(island_removal_mode 0)
			)
			(polygon
				(pts
					(arc
						(start 94.9071 -158.0769)
						(mid 93.0529 -158.0769)
						(end 94.9071 -158.0769)
					)
				)
			)
		)
		(zone
			(layers "F.Cu" "B.Cu" "In1.Cu" "In2.Cu")
			(hatch none 0.5)
			(connect_pads
				(clearance 0)
			)
			(min_thickness 0.25)
			(keepout
				(tracks not_allowed)
				(vias allowed)
				(pads allowed)
				(copperpour not_allowed)
				(footprints allowed)
			)
			(placement
				(enabled no)
				(sheetname "")
			)
			(fill
				(thermal_gap 0.5)
				(thermal_bridge_width 0.5)
				(island_removal_mode 0)
			)
			(polygon
				(pts
					(arc
						(start 94.9071 -151.7269)
						(mid 93.0529 -151.7269)
						(end 94.9071 -151.7269)
					)
				)
			)
		)
		(zone
			(layers "F.Cu" "B.Cu" "In1.Cu" "In2.Cu")
			(hatch none 0.5)
			(connect_pads
				(clearance 0)
			)
			(min_thickness 0.25)
			(keepout
				(tracks not_allowed)
				(vias allowed)
				(pads allowed)
				(copperpour not_allowed)
				(footprints allowed)
			)
			(placement
				(enabled no)
				(sheetname "")
			)
			(fill
				(thermal_gap 0.5)
				(thermal_bridge_width 0.5)
				(island_removal_mode 0)
			)
			(polygon
				(pts
					(arc
						(start 97.4471 -158.0769)
						(mid 95.5929 -158.0769)
						(end 97.4471 -158.0769)
					)
				)
			)
		)
		(zone
			(layers "F.Cu" "B.Cu" "In1.Cu" "In2.Cu")
			(hatch none 0.5)
			(connect_pads
				(clearance 0)
			)
			(min_thickness 0.25)
			(keepout
				(tracks not_allowed)
				(vias allowed)
				(pads allowed)
				(copperpour not_allowed)
				(footprints allowed)
			)
			(placement
				(enabled no)
				(sheetname "")
			)
			(fill
				(thermal_gap 0.5)
				(thermal_bridge_width 0.5)
				(island_removal_mode 0)
			)
			(polygon
				(pts
					(arc
						(start 97.4471 -151.7269)
						(mid 95.5929 -151.7269)
						(end 97.4471 -151.7269)
					)
				)
			)
		)
	)
	(footprint ""
		(layer "F.Cu")
		(at 95.25 -83.232244 90)
		(property "Reference" "J8"
			(at -4.202684 -0.81153 0)
			(unlocked yes)
			(layer "F.SilkS")
			(effects
				(font
					(size 0.7874 0.5842)
					(thickness 0.1524)
				)
				(justify left)
			)
		)
		(property "Value" ""
			(at 0 0 90)
			(layer "F.Fab")
			(effects
				(font
					(size 1.27 1.27)
				)
			)
		)
		(duplicate_pad_numbers_are_jumpers no)
		(fp_line
			(start 1.2192 -2.1082)
			(end 1.2192 2.1082)
			(stroke
				(width 0.1524)
				(type default)
			)
			(layer "F.SilkS")
		)
		(fp_line
			(start -1.2192 -2.1082)
			(end 1.2192 -2.1082)
			(stroke
				(width 0.1524)
				(type default)
			)
			(layer "F.SilkS")
		)
		(fp_line
			(start 1.2192 2.1082)
			(end -1.2192 2.1082)
			(stroke
				(width 0.1524)
				(type default)
			)
			(layer "F.SilkS")
		)
		(fp_line
			(start -1.2192 2.1082)
			(end -1.2192 -2.1082)
			(stroke
				(width 0.1524)
				(type default)
			)
			(layer "F.SilkS")
		)
		(pad "" np_thru_hole circle
			(at -2.8829 -1.27)
			(size 1.0414 1.0414)
			(drill 1.0414)
			(layers "*.Cu" "*.Mask")
			(clearance 0.381)
			(thermal_gap 0.381)
		)
		(pad "" np_thru_hole circle
			(at -2.8829 1.27)
			(size 1.0414 1.0414)
			(drill 1.0414)
			(layers "*.Cu" "*.Mask")
			(clearance 0.381)
			(thermal_gap 0.381)
		)
		(pad "" np_thru_hole circle
			(at 3.4671 -1.27)
			(size 1.0414 1.0414)
			(drill 1.0414)
			(layers "*.Cu" "*.Mask")
			(clearance 0.381)
			(thermal_gap 0.381)
		)
		(pad "" np_thru_hole circle
			(at 3.4671 1.27)
			(size 1.0414 1.0414)
			(drill 1.0414)
			(layers "*.Cu" "*.Mask")
			(clearance 0.381)
			(thermal_gap 0.381)
		)
		(pad "1" smd rect
			(at 0.8255 -0.249936)
			(size 0.3048 0.508)
			(layers "F.Cu" "F.Mask" "F.Paste")
			(net "DELTA_L_85_10INCH_TOP_DN")
		)
		(pad "2" smd rect
			(at 0.8255 0.249936)
			(size 0.3048 0.508)
			(layers "F.Cu" "F.Mask" "F.Paste")
			(net "DELTA_L_85_10INCH_TOP_DP")
		)
		(pad "3" smd circle
			(at 0 0 90)
			(size 0 0)
			(layers "F.Cu" "F.Mask" "F.Paste")
			(net "GND1")
		)
		(zone
			(layer "F.Cu")
			(hatch none 0.5)
			(connect_pads
				(clearance 0)
			)
			(min_thickness 0.25)
			(keepout
				(tracks not_allowed)
				(vias allowed)
				(pads allowed)
				(copperpour not_allowed)
				(footprints allowed)
			)
			(placement
				(enabled no)
				(sheetname "")
			)
			(fill
				(thermal_gap 0.5)
				(thermal_bridge_width 0.5)
				(island_removal_mode 0)
			)
			(polygon
				(pts
					(xy 94.70136 -84.349844) (xy 94.796864 -84.349844) (xy 94.796864 -83.752944) (xy 95.203264 -83.752944)
					(xy 95.203264 -84.349844) (xy 95.296736 -84.349844) (xy 95.296736 -83.752944) (xy 95.703136 -83.752944)
					(xy 95.703136 -84.349844) (xy 95.79864 -84.349844) (xy 95.79864 -83.651344) (xy 94.70136 -83.651344)
				)
			)
		)
		(zone
			(layers "F.Cu" "B.Cu" "In1.Cu" "In2.Cu")
			(hatch none 0.5)
			(connect_pads
				(clearance 0)
			)
			(min_thickness 0.25)
			(keepout
				(tracks not_allowed)
				(vias allowed)
				(pads allowed)
				(copperpour not_allowed)
				(footprints allowed)
			)
			(placement
				(enabled no)
				(sheetname "")
			)
			(fill
				(thermal_gap 0.5)
				(thermal_bridge_width 0.5)
				(island_removal_mode 0)
			)
			(polygon
				(pts
					(arc
						(start 94.9071 -86.699344)
						(mid 93.0529 -86.699344)
						(end 94.9071 -86.699344)
					)
				)
			)
		)
		(zone
			(layers "F.Cu" "B.Cu" "In1.Cu" "In2.Cu")
			(hatch none 0.5)
			(connect_pads
				(clearance 0)
			)
			(min_thickness 0.25)
			(keepout
				(tracks not_allowed)
				(vias allowed)
				(pads allowed)
				(copperpour not_allowed)
				(footprints allowed)
			)
			(placement
				(enabled no)
				(sheetname "")
			)
			(fill
				(thermal_gap 0.5)
				(thermal_bridge_width 0.5)
				(island_removal_mode 0)
			)
			(polygon
				(pts
					(arc
						(start 94.9071 -80.349344)
						(mid 93.0529 -80.349344)
						(end 94.9071 -80.349344)
					)
				)
			)
		)
		(zone
			(layers "F.Cu" "B.Cu" "In1.Cu" "In2.Cu")
			(hatch none 0.5)
			(connect_pads
				(clearance 0)
			)
			(min_thickness 0.25)
			(keepout
				(tracks not_allowed)
				(vias allowed)
				(pads allowed)
				(copperpour not_allowed)
				(footprints allowed)
			)
			(placement
				(enabled no)
				(sheetname "")
			)
			(fill
				(thermal_gap 0.5)
				(thermal_bridge_width 0.5)
				(island_removal_mode 0)
			)
			(polygon
				(pts
					(arc
						(start 97.4471 -86.699344)
						(mid 95.5929 -86.699344)
						(end 97.4471 -86.699344)
					)
				)
			)
		)
		(zone
			(layers "F.Cu" "B.Cu" "In1.Cu" "In2.Cu")
			(hatch none 0.5)
			(connect_pads
				(clearance 0)
			)
			(min_thickness 0.25)
			(keepout
				(tracks not_allowed)
				(vias allowed)
				(pads allowed)
				(copperpour not_allowed)
				(footprints allowed)
			)
			(placement
				(enabled no)
				(sheetname "")
			)
			(fill
				(thermal_gap 0.5)
				(thermal_bridge_width 0.5)
				(island_removal_mode 0)
			)
			(polygon
				(pts
					(arc
						(start 97.4471 -80.349344)
						(mid 95.5929 -80.349344)
						(end 97.4471 -80.349344)
					)
				)
			)
		)
	)
	(footprint ""
		(layer "F.Cu")
		(at 34.600134 -11.02995 180)
		(property "Reference" "H11"
			(at -2.229866 -4.07162 0)
			(unlocked yes)
			(layer "F.SilkS")
			(effects
				(font
					(size 0.7874 0.5842)
					(thickness 0.1524)
				)
				(justify left)
			)
		)
		(property "Value" ""
			(at 0 0 180)
			(layer "F.Fab")
			(effects
				(font
					(size 1.27 1.27)
				)
			)
		)
		(duplicate_pad_numbers_are_jumpers no)
		(fp_line
			(start 4.126992 0)
			(end 4.126992 3.50012)
			(stroke
				(width 0.1524)
				(type default)
			)
			(layer "F.SilkS")
		)
		(fp_line
			(start -4.126992 3.50012)
			(end -4.126992 0)
			(stroke
				(width 0.1524)
				(type default)
			)
			(layer "F.SilkS")
		)
		(fp_arc
			(start 4.126992 3.50012)
			(mid 0 7.627112)
			(end -4.126992 3.50012)
			(stroke
				(width 0.1524)
				(type default)
			)
			(layer "F.SilkS")
		)
		(fp_arc
			(start -4.126992 0)
			(mid 0 -4.126992)
			(end 4.126992 0)
			(stroke
				(width 0.1524)
				(type default)
			)
			(layer "F.SilkS")
		)
		(fp_line
			(start 4.126992 0)
			(end 4.126992 3.50012)
			(stroke
				(width 0.1524)
				(type default)
			)
			(layer "B.SilkS")
		)
		(fp_line
			(start -4.126992 3.50012)
			(end -4.126992 0)
			(stroke
				(width 0.1524)
				(type default)
			)
			(layer "B.SilkS")
		)
		(fp_arc
			(start 4.126992 3.50012)
			(mid 0 7.627112)
			(end -4.126992 3.50012)
			(stroke
				(width 0.1524)
				(type default)
			)
			(layer "B.SilkS")
		)
		(fp_arc
			(start -4.126992 0)
			(mid 0 -4.126992)
			(end 4.126992 0)
			(stroke
				(width 0.1524)
				(type default)
			)
			(layer "B.SilkS")
		)
		(fp_line
			(start 4.126992 0)
			(end 4.126992 3.50012)
			(stroke
				(width 0.1)
				(type default)
			)
			(layer "B.Fab")
		)
		(fp_line
			(start -4.126992 3.50012)
			(end -4.126992 0)
			(stroke
				(width 0.1)
				(type default)
			)
			(layer "B.Fab")
		)
		(fp_arc
			(start 4.126992 3.50012)
			(mid 0 7.627112)
			(end -4.126992 3.50012)
			(stroke
				(width 0.1)
				(type default)
			)
			(layer "B.Fab")
		)
		(fp_arc
			(start -4.126992 0)
			(mid 0 -4.126992)
			(end 4.126992 0)
			(stroke
				(width 0.1)
				(type default)
			)
			(layer "B.Fab")
		)
		(fp_line
			(start 4.126992 0)
			(end 4.126992 3.50012)
			(stroke
				(width 0.1)
				(type default)
			)
			(layer "F.Fab")
		)
		(fp_line
			(start -4.126992 3.50012)
			(end -4.126992 0)
			(stroke
				(width 0.1)
				(type default)
			)
			(layer "F.Fab")
		)
		(fp_arc
			(start 4.126992 3.50012)
			(mid 0 7.627112)
			(end -4.126992 3.50012)
			(stroke
				(width 0.1)
				(type default)
			)
			(layer "F.Fab")
		)
		(fp_arc
			(start -4.126992 0)
			(mid 0 -4.126992)
			(end 4.126992 0)
			(stroke
				(width 0.1)
				(type default)
			)
			(layer "F.Fab")
		)
		(pad "" np_thru_hole circle
			(at 0 0 180)
			(size 3.0226 3.0226)
			(drill 3.0226)
			(layers "*.Cu" "*.Mask")
			(clearance 0.381)
			(thermal_gap 0.381)
		)
		(zone
			(layers "F.Cu" "B.Cu" "In1.Cu" "In2.Cu")
			(hatch none 0.5)
			(connect_pads
				(clearance 0)
			)
			(min_thickness 0.25)
			(keepout
				(tracks not_allowed)
				(vias allowed)
				(pads allowed)
				(copperpour not_allowed)
				(footprints allowed)
			)
			(placement
				(enabled no)
				(sheetname "")
			)
			(fill
				(thermal_gap 0.5)
				(thermal_bridge_width 0.5)
				(island_removal_mode 0)
			)
			(polygon
				(pts
					(arc
						(start 32.26054 -12.639294)
						(mid 34.600134 -17.537768)
						(end 36.939728 -12.639294)
					)
					(arc
						(start 36.939728 -12.639294)
						(mid 36.693555 -12.198846)
						(end 36.608258 -11.701526)
					)
					(arc
						(start 36.608258 -11.02995)
						(mid 34.600134 -9.021826)
						(end 32.59201 -11.02995)
					)
					(arc
						(start 32.59201 -11.701526)
						(mid 32.506704 -12.198839)
						(end 32.26054 -12.639294)
					)
				)
			)
		)
	)
)
